# BASEBOARD_FAB2 (Tioga Pass) — schematic netlist excerpt (pin names and nets, part order shuffled) for the footprints in the layout excerpt that follows; sources: Cadence DE-HDL packaged netlist, KiCad conversion of Wiwynn_Tioga_Pass_MB.brd

R2U46  RES  0.0 5% CHIP  pkg 0402  page 152 : A = H_CPU1_MEMKLM_MEMHOT_LVT3_N ; B = H_CPU1_MEMKLM_MEMHOT_LVT3_BMC_N
R6W20  RES  20.0 1% CHIP  pkg 0402  page 247 : A = SMB_HOST_STBY_LVC3_SDA_R3 ; B = SMB_HOST_STBY_LVC3_SDA
R9P8  RES  0.0 5% CHIP  pkg 0402  page 208 : A = VR_PVCCIN_CPU1_PH4_VCIN ; B = P5V_STBY

(kicad_pcb
	(version 20260206)
	(generator "pcbnew")
	(generator_version "10.0")
	(general
		(thickness 1.6)
		(legacy_teardrops no)
	)
	(paper "A4")
	(title_block
		(title "Wiwynn_Tioga_Pass_MB.brd")
		(comment 1 "Tioga Pass / footprints 3691-3693 of 4770")
	)
	(layers
		(0 "F.Cu" signal "TOP")
		(4 "In1.Cu" signal "L2GND")
		(6 "In2.Cu" signal "L3")
		(8 "In3.Cu" signal "L4GND")
		(10 "In4.Cu" signal "L5")
		(12 "In5.Cu" signal "L6GND")
		(14 "In6.Cu" signal "L7VCC")
		(16 "In7.Cu" signal "L8VCC")
		(18 "In8.Cu" signal "L9GND")
		(20 "In9.Cu" signal "L10")
		(22 "In10.Cu" signal "L11GND")
		(24 "In11.Cu" signal "L12")
		(26 "In12.Cu" signal "L13GND")
		(2 "B.Cu" signal "BOTTOM")
		(9 "F.Adhes" user "F.Adhesive")
		(11 "B.Adhes" user "B.Adhesive")
		(13 "F.Paste" user "Package Geometry/Pastemask Top")
		(15 "B.Paste" user "Package Geometry/Pastemask Bottom")
		(5 "F.SilkS" user "Ref Des/Silkscreen Top")
		(7 "B.SilkS" user "Ref Des/Silkscreen Bottom")
		(1 "F.Mask" user "Board Geometry/Soldermask Top")
		(3 "B.Mask" user "Board Geometry/Soldermask Bottom")
		(17 "Dwgs.User" user "User.Drawings")
		(19 "Cmts.User" user "User.Comments")
		(21 "Eco1.User" user "User.Eco1")
		(23 "Eco2.User" user "User.Eco2")
		(25 "Edge.Cuts" user "Board Geometry/Outline")
		(27 "Margin" user)
		(31 "F.CrtYd" user "Package Geometry/Place Bound Top")
		(29 "B.CrtYd" user "Package Geometry/Place Bound Bottom")
		(35 "F.Fab" user "Ref Des/Assembly Top")
		(33 "B.Fab" user "Ref Des/Assembly Bottom")
	)
	(footprint ""
		(layer "B.Cu")
		(at 450.5325 -22.733 -90)
		(property "Reference" "R6W20"
			(at 0.8382 -0.67818 270)
			(unlocked yes)
			(layer "B.SilkS")
			(effects
				(font
					(size 0.4064 0.254)
					(thickness 0.1524)
				)
				(justify left mirror)
			)
		)
		(property "Value" ""
			(at 0 0 90)
			(layer "B.Fab")
			(effects
				(font
					(size 1.27 1.27)
				)
				(justify mirror)
			)
		)
		(duplicate_pad_numbers_are_jumpers no)
		(fp_poly
			(pts
				(xy 0.2794 -0.1016) (xy -0.2794 -0.1016) (xy -0.2794 0.9906) (xy 0.2794 0.9906)
			)
			(stroke
				(width 0)
				(type default)
			)
			(fill no)
			(layer "B.CrtYd")
		)
		(fp_line
			(start -0.2794 0.9906)
			(end -0.2794 -0.1016)
			(stroke
				(width 0.1)
				(type default)
			)
			(layer "B.Fab")
		)
		(fp_line
			(start 0.2794 0.9906)
			(end -0.2794 0.9906)
			(stroke
				(width 0.1)
				(type default)
			)
			(layer "B.Fab")
		)
		(fp_line
			(start -0.2794 -0.1016)
			(end 0.2794 -0.1016)
			(stroke
				(width 0.1)
				(type default)
			)
			(layer "B.Fab")
		)
		(fp_line
			(start 0.2794 -0.1016)
			(end 0.2794 0.9906)
			(stroke
				(width 0.1)
				(type default)
			)
			(layer "B.Fab")
		)
		(pad "1" smd rect
			(at 0 0 90)
			(size 0.508 0.508)
			(layers "B.Cu" "B.Mask" "B.Paste")
			(net "SMB_HOST_STBY_LVC3_SDA_R3")
		)
		(pad "2" smd rect
			(at 0 0.889 90)
			(size 0.508 0.508)
			(layers "B.Cu" "B.Mask" "B.Paste")
			(net "SMB_HOST_STBY_LVC3_SDA")
		)
		(zone
			(layer "B.Cu")
			(hatch none 0.5)
			(connect_pads
				(clearance 0)
			)
			(min_thickness 0.25)
			(keepout
				(tracks not_allowed)
				(vias allowed)
				(pads allowed)
				(copperpour not_allowed)
				(footprints allowed)
			)
			(placement
				(enabled no)
				(sheetname "")
			)
			(fill
				(thermal_gap 0.5)
				(thermal_bridge_width 0.5)
				(island_removal_mode 0)
			)
			(polygon
				(pts
					(xy 449.8975 -22.479) (xy 449.8975 -22.987) (xy 450.2785 -22.987) (xy 450.2785 -22.479)
				)
			)
		)
		(zone
			(layer "B.Cu")
			(hatch none 0.5)
			(connect_pads
				(clearance 0)
			)
			(min_thickness 0.25)
			(keepout
				(tracks allowed)
				(vias not_allowed)
				(pads allowed)
				(copperpour not_allowed)
				(footprints allowed)
			)
			(placement
				(enabled no)
				(sheetname "")
			)
			(fill
				(thermal_gap 0.5)
				(thermal_bridge_width 0.5)
				(island_removal_mode 0)
			)
			(polygon
				(pts
					(xy 450.2785 -22.479) (xy 450.2785 -22.987) (xy 449.8975 -22.987) (xy 449.8975 -22.479)
				)
			)
		)
	)
	(footprint ""
		(layer "B.Cu")
		(at 413.5755 -18.288 -90)
		(property "Reference" "R2U46"
			(at 0 0 90)
			(layer "B.SilkS")
			(hide yes)
			(effects
				(font
					(size 1.27 1.27)
				)
				(justify mirror)
			)
		)
		(property "Value" ""
			(at 0 0 90)
			(layer "B.Fab")
			(effects
				(font
					(size 1.27 1.27)
				)
				(justify mirror)
			)
		)
		(duplicate_pad_numbers_are_jumpers no)
		(fp_poly
			(pts
				(xy 0.2794 -0.1016) (xy -0.2794 -0.1016) (xy -0.2794 0.9906) (xy 0.2794 0.9906)
			)
			(stroke
				(width 0)
				(type default)
			)
			(fill no)
			(layer "B.CrtYd")
		)
		(fp_line
			(start -0.2794 0.9906)
			(end -0.2794 -0.1016)
			(stroke
				(width 0.1)
				(type default)
			)
			(layer "B.Fab")
		)
		(fp_line
			(start 0.2794 0.9906)
			(end -0.2794 0.9906)
			(stroke
				(width 0.1)
				(type default)
			)
			(layer "B.Fab")
		)
		(fp_line
			(start -0.2794 -0.1016)
			(end 0.2794 -0.1016)
			(stroke
				(width 0.1)
				(type default)
			)
			(layer "B.Fab")
		)
		(fp_line
			(start 0.2794 -0.1016)
			(end 0.2794 0.9906)
			(stroke
				(width 0.1)
				(type default)
			)
			(layer "B.Fab")
		)
		(pad "1" smd rect
			(at 0 0 90)
			(size 0.508 0.508)
			(layers "B.Cu" "B.Mask" "B.Paste")
			(net "H_CPU1_MEMKLM_MEMHOT_LVT3_N")
		)
		(pad "2" smd rect
			(at 0 0.889 90)
			(size 0.508 0.508)
			(layers "B.Cu" "B.Mask" "B.Paste")
			(net "H_CPU1_MEMKLM_MEMHOT_LVT3_BMC_N")
		)
		(zone
			(layer "B.Cu")
			(hatch none 0.5)
			(connect_pads
				(clearance 0)
			)
			(min_thickness 0.25)
			(keepout
				(tracks not_allowed)
				(vias allowed)
				(pads allowed)
				(copperpour not_allowed)
				(footprints allowed)
			)
			(placement
				(enabled no)
				(sheetname "")
			)
			(fill
				(thermal_gap 0.5)
				(thermal_bridge_width 0.5)
				(island_removal_mode 0)
			)
			(polygon
				(pts
					(xy 412.9405 -18.034) (xy 412.9405 -18.542) (xy 413.3215 -18.542) (xy 413.3215 -18.034)
				)
			)
		)
		(zone
			(layer "B.Cu")
			(hatch none 0.5)
			(connect_pads
				(clearance 0)
			)
			(min_thickness 0.25)
			(keepout
				(tracks allowed)
				(vias not_allowed)
				(pads allowed)
				(copperpour not_allowed)
				(footprints allowed)
			)
			(placement
				(enabled no)
				(sheetname "")
			)
			(fill
				(thermal_gap 0.5)
				(thermal_bridge_width 0.5)
				(island_removal_mode 0)
			)
			(polygon
				(pts
					(xy 413.3215 -18.034) (xy 413.3215 -18.542) (xy 412.9405 -18.542) (xy 412.9405 -18.034)
				)
			)
		)
	)
	(footprint ""
		(layer "B.Cu")
		(at 32.2834 -78.9432 90)
		(property "Reference" "R9P8"
			(at 0 0 90)
			(layer "B.SilkS")
			(hide yes)
			(effects
				(font
					(size 1.27 1.27)
				)
				(justify mirror)
			)
		)
		(property "Value" ""
			(at 0 0 90)
			(layer "B.Fab")
			(effects
				(font
					(size 1.27 1.27)
				)
				(justify mirror)
			)
		)
		(duplicate_pad_numbers_are_jumpers no)
		(fp_poly
			(pts
				(xy 0.2794 -0.1016) (xy -0.2794 -0.1016) (xy -0.2794 0.9906) (xy 0.2794 0.9906)
			)
			(stroke
				(width 0)
				(type default)
			)
			(fill no)
			(layer "B.CrtYd")
		)
		(fp_line
			(start 0.2794 -0.1016)
			(end 0.2794 0.9906)
			(stroke
				(width 0.1)
				(type default)
			)
			(layer "B.Fab")
		)
		(fp_line
			(start -0.2794 -0.1016)
			(end 0.2794 -0.1016)
			(stroke
				(width 0.1)
				(type default)
			)
			(layer "B.Fab")
		)
		(fp_line
			(start 0.2794 0.9906)
			(end -0.2794 0.9906)
			(stroke
				(width 0.1)
				(type default)
			)
			(layer "B.Fab")
		)
		(fp_line
			(start -0.2794 0.9906)
			(end -0.2794 -0.1016)
			(stroke
				(width 0.1)
				(type default)
			)
			(layer "B.Fab")
		)
		(pad "1" smd rect
			(at 0 0 270)
			(size 0.508 0.508)
			(layers "B.Cu" "B.Mask" "B.Paste")
			(net "VR_PVCCIN_CPU1_PH4_VCIN")
		)
		(pad "2" smd rect
			(at 0 0.889 270)
			(size 0.508 0.508)
			(layers "B.Cu" "B.Mask" "B.Paste")
			(net "P5V_STBY")
		)
		(zone
			(layer "B.Cu")
			(hatch none 0.5)
			(connect_pads
				(clearance 0)
			)
			(min_thickness 0.25)
			(keepout
				(tracks allowed)
				(vias not_allowed)
				(pads allowed)
				(copperpour not_allowed)
				(footprints allowed)
			)
			(placement
				(enabled no)
				(sheetname "")
			)
			(fill
				(thermal_gap 0.5)
				(thermal_bridge_width 0.5)
				(island_removal_mode 0)
			)
			(polygon
				(pts
					(xy 32.5374 -79.1972) (xy 32.5374 -78.6892) (xy 32.9184 -78.6892) (xy 32.9184 -79.1972)
				)
			)
		)
		(zone
			(layer "B.Cu")
			(hatch none 0.5)
			(connect_pads
				(clearance 0)
			)
			(min_thickness 0.25)
			(keepout
				(tracks not_allowed)
				(vias allowed)
				(pads allowed)
				(copperpour not_allowed)
				(footprints allowed)
			)
			(placement
				(enabled no)
				(sheetname "")
			)
			(fill
				(thermal_gap 0.5)
				(thermal_bridge_width 0.5)
				(island_removal_mode 0)
			)
			(polygon
				(pts
					(xy 32.9184 -79.1972) (xy 32.9184 -78.6892) (xy 32.5374 -78.6892) (xy 32.5374 -79.1972)
				)
			)
		)
	)
)
